#ISCELL
  mstr_misc dns *
  *
#ISCELL
  pure_quanta quanta_title_block_c *
  *
#ISCELL
  standard offpage *
  page154_i120
#ISCELL
  standard offpage *
  page154_i121
#ISCELL
  logical_power universal_gnd *
  page154_i126
#CELL
  pure_quanta q_res *
  page154_i130
#CELL
  pure_quanta q_res *
  page154_i131
#CELL
  pure_quanta q_res *
  page154_i132
#CELL
  pure_quanta q_res *
  page154_i133
#CELL
  pure_quanta q_res *
  page154_i134
#ISCELL
  standard offpage *
  page154_i135
#ISCELL
  standard offpage *
  page154_i136
#CELL
  pure_quanta q_res *
  page154_i137
#ISCELL
  logical_power universal_gnd *
  page154_i138
#ISCELL
  logical_power universal_gnd *
  page154_i139
#CELL
  pure_quanta q_res *
  page154_i140
#ISCELL
  logical_power universal_power *
  page154_i141
#CELL
  pure_quanta q_res *
  page154_i142
#CELL
  pure_quanta q_res *
  page154_i143
#ISCELL
  logical_power universal_gnd *
  page154_i144
#ISCELL
  logical_power universal_power *
  page154_i145
#ISCELL
  standard offpage *
  page154_i146
#CELL
  pure_quanta q_cap *
  page154_i148
#ISCELL
  logical_power universal_gnd *
  page154_i149
#ISCELL
  logical_power universal_gnd *
  page154_i151
#ISCELL
  standard offpage *
  page154_i156
#ISCELL
  standard offpage *
  page154_i163
#ISCELL
  standard offpage *
  page154_i166
#ISCELL
  standard offpage *
  page154_i167
#ISCELL
  logical_power universal_power *
  page154_i168
#CELL
  pure_quanta q_cap *
  page154_i169
#ISCELL
  logical_power universal_gnd *
  page154_i170
#ISCELL
  logical_power universal_power *
  page154_i171
#CELL
  pure_quanta q_res *
  page154_i172
#ISCELL
  standard offpage *
  page154_i173
#ISCELL
  logical_power universal_gnd *
  page154_i174
#ISCELL
  logical_power universal_gnd *
  page154_i176
#CELL
  pure_quanta mosfet_n *
  page154_i177
#ISCELL
  standard offpage *
  page154_i178
#ISCELL
  standard offpage *
  page154_i179
#CELL
  pure_quanta 74lvc1g08w57 *
  page154_i189
#CELL
  pure_quanta 74lvc1g08w57 *
  page154_i190
#CELL
  pure_quanta q_cap *
  page154_i192
#ISCELL
  logical_power universal_gnd *
  page154_i193
#ISCELL
  logical_power universal_power *
  page154_i194
#ISCELL
  standard offpage *
  page154_i201
#ISCELL
  standard offpage *
  page154_i202
#ISCELL
  standard offpage *
  page154_i203
#ISCELL
  standard offpage *
  page154_i205
#CELL
  pure_quanta pca9555apw *
  page154_i206
#ISCELL
  standard offpage *
  page154_i207
#ISCELL
  standard offpage *
  page154_i208
#CELL
  pure_quanta 74lvc1g08w57 *
  page154_i221
#ISCELL
  logical_power universal_power *
  page154_i222
#CELL
  pure_quanta q_cap *
  page154_i223
#ISCELL
  logical_power universal_gnd *
  page154_i224
#ISCELL
  logical_power universal_gnd *
  page154_i225
#ISCELL
  logical_power universal_gnd *
  page154_i226
#ISCELL
  logical_power universal_power *
  page154_i227
#CELL
  pure_quanta apx80929sag7 *
  page154_i228
#CELL
  pure_quanta q_cap *
  page154_i229
#ISCELL
  logical_power universal_gnd *
  page154_i230
#CELL
  pure_quanta q_res *
  page154_i232
#ISCELL
  standard offpage *
  page154_i233
#CELL
  pure_quanta q_res *
  page154_i235
#ISCELL
  logical_power universal_power *
  page154_i236
#CELL
  pure_quanta q_res *
  page154_i237
#CELL
  pure_quanta q_res *
  page154_i238
#ISCELL
  standard offpage *
  page154_i239
#ISCELL
  logical_power universal_power *
  page154_i240
#CELL
  pure_quanta q_cap *
  page154_i241
#ISCELL
  logical_power universal_gnd *
  page154_i242
#CELL
  pure_quanta 74lvc1g08w57 *
  page154_i243
#ISCELL
  logical_power universal_gnd *
  page154_i244
#CELL
  pure_quanta q_res *
  page154_i245
#ISCELL
  standard offpage *
  page154_i246
#CELL
  pure_quanta q_res *
  page154_i247
#ISCELL
  standard offpage *
  page154_i248
#CELL
  pure_quanta q_res *
  page154_i249
#ISCELL
  standard offpage *
  page154_i250
#CELL
  pure_quanta q_res *
  page154_i253
#CELL
  pure_quanta q_res *
  page154_i254
#ISCELL
  logical_power universal_power *
  page154_i255
#CELL
  pure_quanta q_res *
  page154_i256
#CELL
  pure_quanta q_res *
  page154_i257
#ISCELL
  logical_power universal_power *
  page154_i258
